(kicad_pcb
	(version 20260206)
	(generator "pcbnew")
	(generator_version "10.0")
	(general
		(thickness 1.6)
		(legacy_teardrops no)
	)
	(paper "A4")
	(title_block
		(title "04192023_DAF0TMB3IC0_F0TG_MB_C_brd_V02_OCP.brd")
		(comment 1 "Grand Teton / footprints 2123-2127 of 8354")
	)
	(layers
		(0 "F.Cu" signal "TOP")
		(4 "In1.Cu" signal "GND")
		(6 "In2.Cu" signal "IN1")
		(8 "In3.Cu" signal "GND1")
		(10 "In4.Cu" signal "IN2")
		(12 "In5.Cu" signal "GND2")
		(14 "In6.Cu" signal "IN3")
		(16 "In7.Cu" signal "GND3")
		(18 "In8.Cu" signal "VCC")
		(20 "In9.Cu" signal "VCC1")
		(22 "In10.Cu" signal "GND4")
		(24 "In11.Cu" signal "IN4")
		(26 "In12.Cu" signal "GND5")
		(28 "In13.Cu" signal "IN5")
		(30 "In14.Cu" signal "GND6")
		(32 "In15.Cu" signal "IN6")
		(34 "In16.Cu" signal "GND7")
		(2 "B.Cu" signal "BOTTOM")
		(9 "F.Adhes" user "F.Adhesive")
		(11 "B.Adhes" user "B.Adhesive")
		(13 "F.Paste" user "Package Geometry/Pastemask Top")
		(15 "B.Paste" user "Package Geometry/Pastemask Bottom")
		(5 "F.SilkS" user "Ref Des/Silkscreen Top")
		(7 "B.SilkS" user "Ref Des/Silkscreen Bottom")
		(1 "F.Mask" user "Board Geometry/Soldermask Top")
		(3 "B.Mask" user "Board Geometry/Soldermask Bottom")
		(17 "Dwgs.User" user "User.Drawings")
		(19 "Cmts.User" user "User.Comments")
		(21 "Eco1.User" user "User.Eco1")
		(23 "Eco2.User" user "User.Eco2")
		(25 "Edge.Cuts" user "Board Geometry/Outline")
		(27 "Margin" user)
		(31 "F.CrtYd" user "Package Geometry/Place Bound Top")
		(29 "B.CrtYd" user "Package Geometry/Place Bound Bottom")
		(35 "F.Fab" user "Ref Des/Assembly Top")
		(33 "B.Fab" user "Ref Des/Assembly Bottom")
	)
	(footprint ""
		(layer "F.Cu")
		(at 200.854056 -340.655148 180)
		(property "Reference" "PU55"
			(at -5.548884 -2.521712 90)
			(unlocked yes)
			(layer "F.SilkS")
			(effects
				(font
					(size 0.7874 0.5842)
					(thickness 0.1524)
				)
				(justify left)
			)
		)
		(property "Value" ""
			(at 0 0 180)
			(layer "F.Fab")
			(effects
				(font
					(size 1.27 1.27)
				)
			)
		)
		(duplicate_pad_numbers_are_jumpers no)
		(fp_line
			(start 1.549908 -1.9812)
			(end 1.549908 -2.050034)
			(stroke
				(width 0.1524)
				(type default)
			)
			(layer "F.SilkS")
		)
		(fp_line
			(start 1.549908 -2.050034)
			(end 0.5842 -2.050034)
			(stroke
				(width 0.1524)
				(type default)
			)
			(layer "F.SilkS")
		)
		(fp_line
			(start 0 2.050034)
			(end 1.549908 2.050034)
			(stroke
				(width 0.1524)
				(type default)
			)
			(layer "F.SilkS")
		)
		(fp_line
			(start -0.5842 -2.050034)
			(end -1.549908 -2.050034)
			(stroke
				(width 0.1524)
				(type default)
			)
			(layer "F.SilkS")
		)
		(fp_line
			(start -1.549908 2.050034)
			(end -0.5842 2.050034)
			(stroke
				(width 0.1524)
				(type default)
			)
			(layer "F.SilkS")
		)
		(fp_line
			(start -1.549908 1.9812)
			(end -1.549908 2.050034)
			(stroke
				(width 0.1524)
				(type default)
			)
			(layer "F.SilkS")
		)
		(fp_line
			(start -1.549908 -2.050034)
			(end -1.549908 -1.9812)
			(stroke
				(width 0.1524)
				(type default)
			)
			(layer "F.SilkS")
		)
		(fp_poly
			(pts
				(xy -1.9304 -1.700022) (xy -2.641854 -1.344168) (xy -2.641854 -2.055876)
			)
			(stroke
				(width 0)
				(type default)
			)
			(fill yes)
			(layer "F.SilkS")
		)
		(fp_line
			(start 1.549908 2.050034)
			(end 1.549908 -2.050034)
			(stroke
				(width 0.1)
				(type default)
			)
			(layer "F.Fab")
		)
		(fp_line
			(start 1.549908 -2.050034)
			(end -1.549908 -2.050034)
			(stroke
				(width 0.1)
				(type default)
			)
			(layer "F.Fab")
		)
		(fp_line
			(start -1.549908 2.050034)
			(end 1.549908 2.050034)
			(stroke
				(width 0.1)
				(type default)
			)
			(layer "F.Fab")
		)
		(fp_line
			(start -1.549908 -2.050034)
			(end -1.549908 2.050034)
			(stroke
				(width 0.1)
				(type default)
			)
			(layer "F.Fab")
		)
		(fp_poly
			(pts
				(xy -2.9464 -2.208022) (xy -2.9464 -1.192022) (xy -1.9304 -1.700022)
			)
			(stroke
				(width 0)
				(type default)
			)
			(fill yes)
			(layer "F.Fab")
		)
		(pad "1" smd circle
			(at -1.35001 -1.700022 180)
			(size 0 0)
			(layers "F.Cu" "F.Mask" "F.Paste")
			(net "SW_PVDD_33_S5_BST")
		)
		(pad "2" smd rect
			(at -1.400048 -1.199896 270)
			(size 0.1778 0.8128)
			(layers "F.Cu" "F.Mask" "F.Paste")
			(net "GND")
		)
		(pad "3" smd rect
			(at -1.400048 -0.8001 270)
			(size 0.1778 0.8128)
			(layers "F.Cu" "F.Mask" "F.Paste")
			(net "PVDD_33_S5_CS")
		)
		(pad "4" smd rect
			(at -1.400048 -0.40005 270)
			(size 0.1778 0.8128)
			(layers "F.Cu" "F.Mask" "F.Paste")
			(net "PVDD_33_S5_MODE")
		)
		(pad "5" smd rect
			(at -1.400048 0 270)
			(size 0.1778 0.8128)
			(layers "F.Cu" "F.Mask" "F.Paste")
			(net "PVDD_33_S5_REF")
		)
		(pad "6" smd rect
			(at -1.400048 0.40005 270)
			(size 0.1778 0.8128)
			(layers "F.Cu" "F.Mask" "F.Paste")
			(net "GND")
		)
		(pad "7" smd rect
			(at -1.400048 0.8001 270)
			(size 0.1778 0.8128)
			(layers "F.Cu" "F.Mask" "F.Paste")
			(net "PVDD_33_S5_FB")
		)
		(pad "8" smd rect
			(at -1.400048 1.199896 270)
			(size 0.1778 0.8128)
			(layers "F.Cu" "F.Mask" "F.Paste")
			(net "PVDD33_S5_EN")
		)
		(pad "9" smd rect
			(at -1.400048 1.700022 270)
			(size 0.3048 0.8128)
			(layers "F.Cu" "F.Mask" "F.Paste")
			(net "PWRGD_PVDD33_S5")
		)
		(pad "10" smd rect
			(at -0.299974 1.299972 180)
			(size 0.3048 2.0066)
			(layers "F.Cu" "F.Mask" "F.Paste")
			(net "SW_P12V_AUX_PVDD_33_S5_FLT")
		)
		(pad "11_18" smd circle
			(at 1.175004 0.275082 180)
			(size 0 0)
			(layers "F.Cu" "F.Mask" "F.Paste")
			(net "GND")
		)
		(pad "19" smd rect
			(at 1.400048 -1.700022 90)
			(size 0.3048 0.8128)
			(layers "F.Cu" "F.Mask" "F.Paste")
			(net "PVDD_33_S5_VCC")
		)
		(pad "20" smd rect
			(at 0.299974 -1.299972 180)
			(size 0.3048 2.0066)
			(layers "F.Cu" "F.Mask" "F.Paste")
			(net "SW_PVDD_33_S5_SW")
		)
		(pad "21" smd rect
			(at -0.299974 -1.299972 180)
			(size 0.3048 2.0066)
			(layers "F.Cu" "F.Mask" "F.Paste")
			(net "SW_P12V_AUX_PVDD_33_S5_FLT")
		)
	)
	(footprint ""
		(layer "F.Cu")
		(at 123.767342 -16.50111 180)
		(property "Reference" "R4200"
			(at 0 0 180)
			(layer "F.SilkS")
			(hide yes)
			(effects
				(font
					(size 1.27 1.27)
				)
			)
		)
		(property "Value" ""
			(at 0 0 180)
			(layer "F.Fab")
			(effects
				(font
					(size 1.27 1.27)
				)
			)
		)
		(duplicate_pad_numbers_are_jumpers no)
		(fp_line
			(start 0.7874 0.4064)
			(end -0.7874 0.4064)
			(stroke
				(width 0.1524)
				(type default)
			)
			(layer "F.SilkS")
		)
		(fp_line
			(start 0.7874 -0.4064)
			(end 0.7874 0.4064)
			(stroke
				(width 0.1524)
				(type default)
			)
			(layer "F.SilkS")
		)
		(fp_line
			(start -0.7874 0.4064)
			(end -0.7874 -0.4064)
			(stroke
				(width 0.1524)
				(type default)
			)
			(layer "F.SilkS")
		)
		(fp_line
			(start -0.7874 -0.4064)
			(end 0.7874 -0.4064)
			(stroke
				(width 0.1524)
				(type default)
			)
			(layer "F.SilkS")
		)
		(fp_line
			(start 0.67945 0.3048)
			(end 0.120396 0.3048)
			(stroke
				(width 0.1)
				(type default)
			)
			(layer "F.Fab")
		)
		(fp_line
			(start 0.67945 -0.3048)
			(end 0.67945 0.3048)
			(stroke
				(width 0.1)
				(type default)
			)
			(layer "F.Fab")
		)
		(fp_line
			(start 0.12065 -0.2794)
			(end 0.12065 -0.3048)
			(stroke
				(width 0.1)
				(type default)
			)
			(layer "F.Fab")
		)
		(fp_line
			(start 0.12065 -0.3048)
			(end 0.67945 -0.3048)
			(stroke
				(width 0.1)
				(type default)
			)
			(layer "F.Fab")
		)
		(fp_line
			(start 0.120396 0.3048)
			(end 0.120396 0.2794)
			(stroke
				(width 0.1)
				(type default)
			)
			(layer "F.Fab")
		)
		(fp_line
			(start 0.120396 0.2794)
			(end -0.12065 0.2794)
			(stroke
				(width 0.1)
				(type default)
			)
			(layer "F.Fab")
		)
		(fp_line
			(start -0.12065 0.3048)
			(end -0.67945 0.3048)
			(stroke
				(width 0.1)
				(type default)
			)
			(layer "F.Fab")
		)
		(fp_line
			(start -0.12065 0.2794)
			(end -0.12065 0.3048)
			(stroke
				(width 0.1)
				(type default)
			)
			(layer "F.Fab")
		)
		(fp_line
			(start -0.12065 -0.2794)
			(end 0.12065 -0.2794)
			(stroke
				(width 0.1)
				(type default)
			)
			(layer "F.Fab")
		)
		(fp_line
			(start -0.12065 -0.305054)
			(end -0.12065 -0.2794)
			(stroke
				(width 0.1)
				(type default)
			)
			(layer "F.Fab")
		)
		(fp_line
			(start -0.67945 0.3048)
			(end -0.67945 -0.305054)
			(stroke
				(width 0.1)
				(type default)
			)
			(layer "F.Fab")
		)
		(fp_line
			(start -0.67945 -0.305054)
			(end -0.12065 -0.305054)
			(stroke
				(width 0.1)
				(type default)
			)
			(layer "F.Fab")
		)
		(pad "1" smd circle
			(at -0.40005 0 180)
			(size 0 0)
			(layers "F.Cu" "F.Mask" "F.Paste")
			(net "P3V3_AUX")
		)
		(pad "2" smd circle
			(at 0.40005 0 180)
			(size 0 0)
			(layers "F.Cu" "F.Mask" "F.Paste")
			(net "U273_3_ADD0")
		)
	)
	(footprint ""
		(layer "F.Cu")
		(at 384.113278 -143.250158 180)
		(property "Reference" "R8313"
			(at 0 0 180)
			(layer "F.SilkS")
			(hide yes)
			(effects
				(font
					(size 1.27 1.27)
				)
			)
		)
		(property "Value" ""
			(at 0 0 180)
			(layer "F.Fab")
			(effects
				(font
					(size 1.27 1.27)
				)
			)
		)
		(duplicate_pad_numbers_are_jumpers no)
		(fp_line
			(start 0.7874 0.4064)
			(end -0.7874 0.4064)
			(stroke
				(width 0.1524)
				(type default)
			)
			(layer "F.SilkS")
		)
		(fp_line
			(start 0.7874 -0.4064)
			(end 0.7874 0.4064)
			(stroke
				(width 0.1524)
				(type default)
			)
			(layer "F.SilkS")
		)
		(fp_line
			(start -0.7874 0.4064)
			(end -0.7874 -0.4064)
			(stroke
				(width 0.1524)
				(type default)
			)
			(layer "F.SilkS")
		)
		(fp_line
			(start -0.7874 -0.4064)
			(end 0.7874 -0.4064)
			(stroke
				(width 0.1524)
				(type default)
			)
			(layer "F.SilkS")
		)
		(fp_line
			(start 0.67945 0.3048)
			(end 0.120396 0.3048)
			(stroke
				(width 0.1)
				(type default)
			)
			(layer "F.Fab")
		)
		(fp_line
			(start 0.67945 -0.3048)
			(end 0.67945 0.3048)
			(stroke
				(width 0.1)
				(type default)
			)
			(layer "F.Fab")
		)
		(fp_line
			(start 0.12065 -0.2794)
			(end 0.12065 -0.3048)
			(stroke
				(width 0.1)
				(type default)
			)
			(layer "F.Fab")
		)
		(fp_line
			(start 0.12065 -0.3048)
			(end 0.67945 -0.3048)
			(stroke
				(width 0.1)
				(type default)
			)
			(layer "F.Fab")
		)
		(fp_line
			(start 0.120396 0.3048)
			(end 0.120396 0.2794)
			(stroke
				(width 0.1)
				(type default)
			)
			(layer "F.Fab")
		)
		(fp_line
			(start 0.120396 0.2794)
			(end -0.12065 0.2794)
			(stroke
				(width 0.1)
				(type default)
			)
			(layer "F.Fab")
		)
		(fp_line
			(start -0.12065 0.3048)
			(end -0.67945 0.3048)
			(stroke
				(width 0.1)
				(type default)
			)
			(layer "F.Fab")
		)
		(fp_line
			(start -0.12065 0.2794)
			(end -0.12065 0.3048)
			(stroke
				(width 0.1)
				(type default)
			)
			(layer "F.Fab")
		)
		(fp_line
			(start -0.12065 -0.2794)
			(end 0.12065 -0.2794)
			(stroke
				(width 0.1)
				(type default)
			)
			(layer "F.Fab")
		)
		(fp_line
			(start -0.12065 -0.305054)
			(end -0.12065 -0.2794)
			(stroke
				(width 0.1)
				(type default)
			)
			(layer "F.Fab")
		)
		(fp_line
			(start -0.67945 0.3048)
			(end -0.67945 -0.305054)
			(stroke
				(width 0.1)
				(type default)
			)
			(layer "F.Fab")
		)
		(fp_line
			(start -0.67945 -0.305054)
			(end -0.12065 -0.305054)
			(stroke
				(width 0.1)
				(type default)
			)
			(layer "F.Fab")
		)
		(pad "1" smd circle
			(at -0.40005 0 180)
			(size 0 0)
			(layers "F.Cu" "F.Mask" "F.Paste")
			(net "PVDD18_S5_P0")
		)
		(pad "2" smd circle
			(at 0.40005 0 180)
			(size 0 0)
			(layers "F.Cu" "F.Mask" "F.Paste")
			(net "PVDDCR_CPU0_P0_OCP_N_R")
		)
	)
	(footprint ""
		(layer "F.Cu")
		(at 34.633662 -419.249098 90)
		(property "Reference" "R3289"
			(at 0 0 90)
			(layer "F.SilkS")
			(hide yes)
			(effects
				(font
					(size 1.27 1.27)
				)
			)
		)
		(property "Value" ""
			(at 0 0 90)
			(layer "F.Fab")
			(effects
				(font
					(size 1.27 1.27)
				)
			)
		)
		(duplicate_pad_numbers_are_jumpers no)
		(fp_line
			(start 0.7874 -0.4064)
			(end 0.7874 0.4064)
			(stroke
				(width 0.1524)
				(type default)
			)
			(layer "F.SilkS")
		)
		(fp_line
			(start -0.7874 -0.4064)
			(end 0.7874 -0.4064)
			(stroke
				(width 0.1524)
				(type default)
			)
			(layer "F.SilkS")
		)
		(fp_line
			(start 0.7874 0.4064)
			(end -0.7874 0.4064)
			(stroke
				(width 0.1524)
				(type default)
			)
			(layer "F.SilkS")
		)
		(fp_line
			(start -0.7874 0.4064)
			(end -0.7874 -0.4064)
			(stroke
				(width 0.1524)
				(type default)
			)
			(layer "F.SilkS")
		)
		(fp_line
			(start -0.12065 -0.305054)
			(end -0.12065 -0.2794)
			(stroke
				(width 0.1)
				(type default)
			)
			(layer "F.Fab")
		)
		(fp_line
			(start -0.67945 -0.305054)
			(end -0.12065 -0.305054)
			(stroke
				(width 0.1)
				(type default)
			)
			(layer "F.Fab")
		)
		(fp_line
			(start 0.67945 -0.3048)
			(end 0.67945 0.3048)
			(stroke
				(width 0.1)
				(type default)
			)
			(layer "F.Fab")
		)
		(fp_line
			(start 0.12065 -0.3048)
			(end 0.67945 -0.3048)
			(stroke
				(width 0.1)
				(type default)
			)
			(layer "F.Fab")
		)
		(fp_line
			(start 0.12065 -0.2794)
			(end 0.12065 -0.3048)
			(stroke
				(width 0.1)
				(type default)
			)
			(layer "F.Fab")
		)
		(fp_line
			(start -0.12065 -0.2794)
			(end 0.12065 -0.2794)
			(stroke
				(width 0.1)
				(type default)
			)
			(layer "F.Fab")
		)
		(fp_line
			(start 0.120396 0.2794)
			(end -0.12065 0.2794)
			(stroke
				(width 0.1)
				(type default)
			)
			(layer "F.Fab")
		)
		(fp_line
			(start -0.12065 0.2794)
			(end -0.12065 0.3048)
			(stroke
				(width 0.1)
				(type default)
			)
			(layer "F.Fab")
		)
		(fp_line
			(start 0.67945 0.3048)
			(end 0.120396 0.3048)
			(stroke
				(width 0.1)
				(type default)
			)
			(layer "F.Fab")
		)
		(fp_line
			(start 0.120396 0.3048)
			(end 0.120396 0.2794)
			(stroke
				(width 0.1)
				(type default)
			)
			(layer "F.Fab")
		)
		(fp_line
			(start -0.12065 0.3048)
			(end -0.67945 0.3048)
			(stroke
				(width 0.1)
				(type default)
			)
			(layer "F.Fab")
		)
		(fp_line
			(start -0.67945 0.3048)
			(end -0.67945 -0.305054)
			(stroke
				(width 0.1)
				(type default)
			)
			(layer "F.Fab")
		)
		(pad "1" smd circle
			(at -0.40005 0 90)
			(size 0 0)
			(layers "F.Cu" "F.Mask" "F.Paste")
			(net "P3V3_AUX")
		)
		(pad "2" smd circle
			(at 0.40005 0 90)
			(size 0 0)
			(layers "F.Cu" "F.Mask" "F.Paste")
			(net "FM_P2E_SWA")
		)
	)
	(footprint ""
		(layer "F.Cu")
		(at 91.770454 -335.027524 -90)
		(property "Reference" "PC423_C1P1_5"
			(at 0 0 270)
			(layer "F.SilkS")
			(hide yes)
			(effects
				(font
					(size 1.27 1.27)
				)
			)
		)
		(property "Value" ""
			(at 0 0 270)
			(layer "F.Fab")
			(effects
				(font
					(size 1.27 1.27)
				)
			)
		)
		(duplicate_pad_numbers_are_jumpers no)
		(fp_line
			(start -0.7874 0.4064)
			(end -0.7874 -0.4064)
			(stroke
				(width 0.1524)
				(type default)
			)
			(layer "F.SilkS")
		)
		(fp_line
			(start 0.7874 0.4064)
			(end -0.7874 0.4064)
			(stroke
				(width 0.1524)
				(type default)
			)
			(layer "F.SilkS")
		)
		(fp_line
			(start -0.7874 -0.4064)
			(end 0.7874 -0.4064)
			(stroke
				(width 0.1524)
				(type default)
			)
			(layer "F.SilkS")
		)
		(fp_line
			(start 0.7874 -0.4064)
			(end 0.7874 0.4064)
			(stroke
				(width 0.1524)
				(type default)
			)
			(layer "F.SilkS")
		)
		(fp_line
			(start -0.67945 0.3048)
			(end -0.67945 -0.305054)
			(stroke
				(width 0.1)
				(type default)
			)
			(layer "F.Fab")
		)
		(fp_line
			(start -0.12065 0.3048)
			(end -0.67945 0.3048)
			(stroke
				(width 0.1)
				(type default)
			)
			(layer "F.Fab")
		)
		(fp_line
			(start 0.120396 0.3048)
			(end 0.120396 0.2794)
			(stroke
				(width 0.1)
				(type default)
			)
			(layer "F.Fab")
		)
		(fp_line
			(start 0.67945 0.3048)
			(end 0.120396 0.3048)
			(stroke
				(width 0.1)
				(type default)
			)
			(layer "F.Fab")
		)
		(fp_line
			(start -0.12065 0.2794)
			(end -0.12065 0.3048)
			(stroke
				(width 0.1)
				(type default)
			)
			(layer "F.Fab")
		)
		(fp_line
			(start 0.120396 0.2794)
			(end -0.12065 0.2794)
			(stroke
				(width 0.1)
				(type default)
			)
			(layer "F.Fab")
		)
		(fp_line
			(start -0.12065 -0.2794)
			(end 0.12065 -0.2794)
			(stroke
				(width 0.1)
				(type default)
			)
			(layer "F.Fab")
		)
		(fp_line
			(start 0.12065 -0.2794)
			(end 0.12065 -0.3048)
			(stroke
				(width 0.1)
				(type default)
			)
			(layer "F.Fab")
		)
		(fp_line
			(start 0.12065 -0.3048)
			(end 0.67945 -0.3048)
			(stroke
				(width 0.1)
				(type default)
			)
			(layer "F.Fab")
		)
		(fp_line
			(start 0.67945 -0.3048)
			(end 0.67945 0.3048)
			(stroke
				(width 0.1)
				(type default)
			)
			(layer "F.Fab")
		)
		(fp_line
			(start -0.67945 -0.305054)
			(end -0.12065 -0.305054)
			(stroke
				(width 0.1)
				(type default)
			)
			(layer "F.Fab")
		)
		(fp_line
			(start -0.12065 -0.305054)
			(end -0.12065 -0.2794)
			(stroke
				(width 0.1)
				(type default)
			)
			(layer "F.Fab")
		)
		(pad "1" smd circle
			(at -0.40005 0 270)
			(size 0 0)
			(layers "F.Cu" "F.Mask" "F.Paste")
			(net "PVDDCR_CPU1_P1_PVCC")
		)
		(pad "2" smd circle
			(at 0.40005 0 270)
			(size 0 0)
			(layers "F.Cu" "F.Mask" "F.Paste")
			(net "GND")
		)
	)
)
